(kicad_pcb
	(version 20260206)
	(generator "pcbnew")
	(generator_version "10.0")
	(general
		(thickness 1.6)
		(legacy_teardrops no)
	)
	(paper "A4")
	(title_block
		(title "04192023_DAF0TMB3IC0_F0TG_MB_C_brd_V02_OCP.brd")
		(comment 1 "Grand Teton / footprints 6573-6580 of 8354")
	)
	(layers
		(0 "F.Cu" signal "TOP")
		(4 "In1.Cu" signal "GND")
		(6 "In2.Cu" signal "IN1")
		(8 "In3.Cu" signal "GND1")
		(10 "In4.Cu" signal "IN2")
		(12 "In5.Cu" signal "GND2")
		(14 "In6.Cu" signal "IN3")
		(16 "In7.Cu" signal "GND3")
		(18 "In8.Cu" signal "VCC")
		(20 "In9.Cu" signal "VCC1")
		(22 "In10.Cu" signal "GND4")
		(24 "In11.Cu" signal "IN4")
		(26 "In12.Cu" signal "GND5")
		(28 "In13.Cu" signal "IN5")
		(30 "In14.Cu" signal "GND6")
		(32 "In15.Cu" signal "IN6")
		(34 "In16.Cu" signal "GND7")
		(2 "B.Cu" signal "BOTTOM")
		(9 "F.Adhes" user "F.Adhesive")
		(11 "B.Adhes" user "B.Adhesive")
		(13 "F.Paste" user "Package Geometry/Pastemask Top")
		(15 "B.Paste" user "Package Geometry/Pastemask Bottom")
		(5 "F.SilkS" user "Ref Des/Silkscreen Top")
		(7 "B.SilkS" user "Ref Des/Silkscreen Bottom")
		(1 "F.Mask" user "Board Geometry/Soldermask Top")
		(3 "B.Mask" user "Board Geometry/Soldermask Bottom")
		(17 "Dwgs.User" user "User.Drawings")
		(19 "Cmts.User" user "User.Comments")
		(21 "Eco1.User" user "User.Eco1")
		(23 "Eco2.User" user "User.Eco2")
		(25 "Edge.Cuts" user "Board Geometry/Outline")
		(27 "Margin" user)
		(31 "F.CrtYd" user "Package Geometry/Place Bound Top")
		(29 "B.CrtYd" user "Package Geometry/Place Bound Bottom")
		(35 "F.Fab" user "Ref Des/Assembly Top")
		(33 "B.Fab" user "Ref Des/Assembly Bottom")
	)
	(footprint ""
		(layer "B.Cu")
		(at 403.088856 -168.717468 -90)
		(property "Reference" "PC592_2"
			(at 0 0 90)
			(layer "B.SilkS")
			(hide yes)
			(effects
				(font
					(size 1.27 1.27)
				)
				(justify mirror)
			)
		)
		(property "Value" ""
			(at 0 0 90)
			(layer "B.Fab")
			(effects
				(font
					(size 1.27 1.27)
				)
				(justify mirror)
			)
		)
		(duplicate_pad_numbers_are_jumpers no)
		(fp_line
			(start -1.524 0.762)
			(end 1.524 0.762)
			(stroke
				(width 0.1524)
				(type default)
			)
			(layer "B.SilkS")
		)
		(fp_line
			(start 1.524 0.762)
			(end 1.524 -0.762)
			(stroke
				(width 0.1524)
				(type default)
			)
			(layer "B.SilkS")
		)
		(fp_line
			(start -1.524 -0.762)
			(end -1.524 0.762)
			(stroke
				(width 0.1524)
				(type default)
			)
			(layer "B.SilkS")
		)
		(fp_line
			(start 1.524 -0.762)
			(end -1.524 -0.762)
			(stroke
				(width 0.1524)
				(type default)
			)
			(layer "B.SilkS")
		)
		(fp_line
			(start -1.1049 0.724916)
			(end -1.1049 -0.724916)
			(stroke
				(width 0.1)
				(type default)
			)
			(layer "B.Fab")
		)
		(fp_line
			(start 1.1049 0.724916)
			(end -1.1049 0.724916)
			(stroke
				(width 0.1)
				(type default)
			)
			(layer "B.Fab")
		)
		(fp_line
			(start -1.1049 -0.724916)
			(end 1.1049 -0.724916)
			(stroke
				(width 0.1)
				(type default)
			)
			(layer "B.Fab")
		)
		(fp_line
			(start 1.1049 -0.724916)
			(end 1.1049 0.724916)
			(stroke
				(width 0.1)
				(type default)
			)
			(layer "B.Fab")
		)
		(pad "1" smd rect
			(at 0.889 0 270)
			(size 1.016 1.27)
			(layers "B.Cu" "B.Mask" "B.Paste")
			(net "SW_P12V_AUX_PVDDCR_SOC_P0_FLT")
		)
		(pad "2" smd rect
			(at -0.889 0 270)
			(size 1.016 1.27)
			(layers "B.Cu" "B.Mask" "B.Paste")
			(net "GND")
		)
	)
	(footprint ""
		(layer "B.Cu")
		(at 360.366056 -256.012188 -90)
		(property "Reference" "C2135"
			(at 0 0 90)
			(layer "B.SilkS")
			(hide yes)
			(effects
				(font
					(size 1.27 1.27)
				)
				(justify mirror)
			)
		)
		(property "Value" ""
			(at 0 0 90)
			(layer "B.Fab")
			(effects
				(font
					(size 1.27 1.27)
				)
				(justify mirror)
			)
		)
		(duplicate_pad_numbers_are_jumpers no)
		(fp_line
			(start -0.7874 0.4064)
			(end 0.7874 0.4064)
			(stroke
				(width 0.1524)
				(type default)
			)
			(layer "B.SilkS")
		)
		(fp_line
			(start 0.7874 0.4064)
			(end 0.7874 -0.4064)
			(stroke
				(width 0.1524)
				(type default)
			)
			(layer "B.SilkS")
		)
		(fp_line
			(start -0.7874 -0.4064)
			(end -0.7874 0.4064)
			(stroke
				(width 0.1524)
				(type default)
			)
			(layer "B.SilkS")
		)
		(fp_line
			(start 0.7874 -0.4064)
			(end -0.7874 -0.4064)
			(stroke
				(width 0.1524)
				(type default)
			)
			(layer "B.SilkS")
		)
		(fp_line
			(start -0.67945 0.3048)
			(end -0.120396 0.3048)
			(stroke
				(width 0.1)
				(type default)
			)
			(layer "B.Fab")
		)
		(fp_line
			(start -0.120396 0.3048)
			(end -0.120396 0.2794)
			(stroke
				(width 0.1)
				(type default)
			)
			(layer "B.Fab")
		)
		(fp_line
			(start 0.12065 0.3048)
			(end 0.67945 0.3048)
			(stroke
				(width 0.1)
				(type default)
			)
			(layer "B.Fab")
		)
		(fp_line
			(start 0.67945 0.3048)
			(end 0.67945 -0.305054)
			(stroke
				(width 0.1)
				(type default)
			)
			(layer "B.Fab")
		)
		(fp_line
			(start -0.120396 0.2794)
			(end 0.12065 0.2794)
			(stroke
				(width 0.1)
				(type default)
			)
			(layer "B.Fab")
		)
		(fp_line
			(start 0.12065 0.2794)
			(end 0.12065 0.3048)
			(stroke
				(width 0.1)
				(type default)
			)
			(layer "B.Fab")
		)
		(fp_line
			(start -0.12065 -0.2794)
			(end -0.12065 -0.3048)
			(stroke
				(width 0.1)
				(type default)
			)
			(layer "B.Fab")
		)
		(fp_line
			(start 0.12065 -0.2794)
			(end -0.12065 -0.2794)
			(stroke
				(width 0.1)
				(type default)
			)
			(layer "B.Fab")
		)
		(fp_line
			(start -0.67945 -0.3048)
			(end -0.67945 0.3048)
			(stroke
				(width 0.1)
				(type default)
			)
			(layer "B.Fab")
		)
		(fp_line
			(start -0.12065 -0.3048)
			(end -0.67945 -0.3048)
			(stroke
				(width 0.1)
				(type default)
			)
			(layer "B.Fab")
		)
		(fp_line
			(start 0.12065 -0.305054)
			(end 0.12065 -0.2794)
			(stroke
				(width 0.1)
				(type default)
			)
			(layer "B.Fab")
		)
		(fp_line
			(start 0.67945 -0.305054)
			(end 0.12065 -0.305054)
			(stroke
				(width 0.1)
				(type default)
			)
			(layer "B.Fab")
		)
		(pad "1" smd circle
			(at 0.40005 0 90)
			(size 0 0)
			(layers "B.Cu" "B.Mask" "B.Paste")
			(net "PVDDCR_SOC_P0")
		)
		(pad "2" smd circle
			(at -0.40005 0 90)
			(size 0 0)
			(layers "B.Cu" "B.Mask" "B.Paste")
			(net "GND")
		)
	)
	(footprint ""
		(layer "B.Cu")
		(at 406.717754 -330.93533)
		(property "Reference" "R5028"
			(at 0 0 0)
			(layer "B.SilkS")
			(hide yes)
			(effects
				(font
					(size 1.27 1.27)
				)
				(justify mirror)
			)
		)
		(property "Value" ""
			(at 0 0 0)
			(layer "B.Fab")
			(effects
				(font
					(size 1.27 1.27)
				)
				(justify mirror)
			)
		)
		(duplicate_pad_numbers_are_jumpers no)
		(fp_line
			(start -0.7874 -0.4064)
			(end -0.7874 0.4064)
			(stroke
				(width 0.1524)
				(type default)
			)
			(layer "B.SilkS")
		)
		(fp_line
			(start -0.7874 0.4064)
			(end 0.7874 0.4064)
			(stroke
				(width 0.1524)
				(type default)
			)
			(layer "B.SilkS")
		)
		(fp_line
			(start 0.7874 -0.4064)
			(end -0.7874 -0.4064)
			(stroke
				(width 0.1524)
				(type default)
			)
			(layer "B.SilkS")
		)
		(fp_line
			(start 0.7874 0.4064)
			(end 0.7874 -0.4064)
			(stroke
				(width 0.1524)
				(type default)
			)
			(layer "B.SilkS")
		)
		(fp_line
			(start -0.67945 -0.3048)
			(end -0.67945 0.3048)
			(stroke
				(width 0.1)
				(type default)
			)
			(layer "B.Fab")
		)
		(fp_line
			(start -0.67945 0.3048)
			(end -0.120396 0.3048)
			(stroke
				(width 0.1)
				(type default)
			)
			(layer "B.Fab")
		)
		(fp_line
			(start -0.12065 -0.3048)
			(end -0.67945 -0.3048)
			(stroke
				(width 0.1)
				(type default)
			)
			(layer "B.Fab")
		)
		(fp_line
			(start -0.12065 -0.2794)
			(end -0.12065 -0.3048)
			(stroke
				(width 0.1)
				(type default)
			)
			(layer "B.Fab")
		)
		(fp_line
			(start -0.120396 0.2794)
			(end 0.12065 0.2794)
			(stroke
				(width 0.1)
				(type default)
			)
			(layer "B.Fab")
		)
		(fp_line
			(start -0.120396 0.3048)
			(end -0.120396 0.2794)
			(stroke
				(width 0.1)
				(type default)
			)
			(layer "B.Fab")
		)
		(fp_line
			(start 0.12065 -0.305054)
			(end 0.12065 -0.2794)
			(stroke
				(width 0.1)
				(type default)
			)
			(layer "B.Fab")
		)
		(fp_line
			(start 0.12065 -0.2794)
			(end -0.12065 -0.2794)
			(stroke
				(width 0.1)
				(type default)
			)
			(layer "B.Fab")
		)
		(fp_line
			(start 0.12065 0.2794)
			(end 0.12065 0.3048)
			(stroke
				(width 0.1)
				(type default)
			)
			(layer "B.Fab")
		)
		(fp_line
			(start 0.12065 0.3048)
			(end 0.67945 0.3048)
			(stroke
				(width 0.1)
				(type default)
			)
			(layer "B.Fab")
		)
		(fp_line
			(start 0.67945 -0.305054)
			(end 0.12065 -0.305054)
			(stroke
				(width 0.1)
				(type default)
			)
			(layer "B.Fab")
		)
		(fp_line
			(start 0.67945 0.3048)
			(end 0.67945 -0.305054)
			(stroke
				(width 0.1)
				(type default)
			)
			(layer "B.Fab")
		)
		(pad "1" smd circle
			(at 0.40005 0 180)
			(size 0 0)
			(layers "B.Cu" "B.Mask" "B.Paste")
			(net "GND")
		)
		(pad "2" smd circle
			(at -0.40005 0 180)
			(size 0 0)
			(layers "B.Cu" "B.Mask" "B.Paste")
			(net "IRQ_BMC_SMI_N")
		)
	)
	(footprint ""
		(layer "B.Cu")
		(at 479.100642 -353.385882)
		(property "Reference" "DB15"
			(at 2.448814 -5.35051 270)
			(unlocked yes)
			(layer "B.SilkS")
			(effects
				(font
					(size 0.7874 0.5842)
					(thickness 0.1524)
				)
				(justify left mirror)
			)
		)
		(property "Value" ""
			(at 0 0 0)
			(layer "B.Fab")
			(effects
				(font
					(size 1.27 1.27)
				)
				(justify mirror)
			)
		)
		(duplicate_pad_numbers_are_jumpers no)
		(fp_line
			(start -3.330702 -4.771136)
			(end 0 4.011168)
			(stroke
				(width 0.1524)
				(type default)
			)
			(layer "B.SilkS")
		)
		(fp_line
			(start 0 4.011168)
			(end 3.330702 -4.771136)
			(stroke
				(width 0.1524)
				(type default)
			)
			(layer "B.SilkS")
		)
		(fp_line
			(start 3.330702 -4.771136)
			(end -3.330702 -4.771136)
			(stroke
				(width 0.1524)
				(type default)
			)
			(layer "B.SilkS")
		)
		(fp_line
			(start -3.330702 -4.771136)
			(end 0 4.011168)
			(stroke
				(width 0.1)
				(type default)
			)
			(layer "B.Fab")
		)
		(fp_line
			(start 0 4.011168)
			(end 3.330702 -4.771136)
			(stroke
				(width 0.1)
				(type default)
			)
			(layer "B.Fab")
		)
		(fp_line
			(start 3.330702 -4.771136)
			(end -3.330702 -4.771136)
			(stroke
				(width 0.1)
				(type default)
			)
			(layer "B.Fab")
		)
		(pad "1" thru_hole circle
			(at 0 0 180)
			(size 2.159 2.159)
			(drill 1.7018)
			(layers "*.Cu" "*.Mask")
			(remove_unused_layers no)
			(net "T1_GND")
			(clearance 0.0254)
			(thermal_gap 0.0254)
		)
		(pad "2" thru_hole circle
			(at 1.27 -3.348736 180)
			(size 2.159 2.159)
			(drill 1.7018)
			(layers "*.Cu" "*.Mask")
			(remove_unused_layers no)
			(net "TDR_SE_50_OHM_IN5")
			(clearance 0.0254)
			(thermal_gap 0.0254)
		)
		(pad "3" thru_hole circle
			(at -1.27 -3.348736 180)
			(size 2.159 2.159)
			(drill 1.7018)
			(layers "*.Cu" "*.Mask")
			(remove_unused_layers no)
			(net "TDR_SE_50_OHM_IN5")
			(clearance 0.0254)
			(thermal_gap 0.0254)
		)
	)
	(footprint ""
		(layer "B.Cu")
		(at 117.769386 -264.354564)
		(property "Reference" "C2128"
			(at 0 0 0)
			(layer "B.SilkS")
			(hide yes)
			(effects
				(font
					(size 1.27 1.27)
				)
				(justify mirror)
			)
		)
		(property "Value" ""
			(at 0 0 0)
			(layer "B.Fab")
			(effects
				(font
					(size 1.27 1.27)
				)
				(justify mirror)
			)
		)
		(duplicate_pad_numbers_are_jumpers no)
		(fp_line
			(start -0.7874 -0.4064)
			(end -0.7874 0.4064)
			(stroke
				(width 0.1524)
				(type default)
			)
			(layer "B.SilkS")
		)
		(fp_line
			(start -0.7874 0.4064)
			(end 0.7874 0.4064)
			(stroke
				(width 0.1524)
				(type default)
			)
			(layer "B.SilkS")
		)
		(fp_line
			(start 0.7874 -0.4064)
			(end -0.7874 -0.4064)
			(stroke
				(width 0.1524)
				(type default)
			)
			(layer "B.SilkS")
		)
		(fp_line
			(start 0.7874 0.4064)
			(end 0.7874 -0.4064)
			(stroke
				(width 0.1524)
				(type default)
			)
			(layer "B.SilkS")
		)
		(fp_line
			(start -0.67945 -0.3048)
			(end -0.67945 0.3048)
			(stroke
				(width 0.1)
				(type default)
			)
			(layer "B.Fab")
		)
		(fp_line
			(start -0.67945 0.3048)
			(end -0.120396 0.3048)
			(stroke
				(width 0.1)
				(type default)
			)
			(layer "B.Fab")
		)
		(fp_line
			(start -0.12065 -0.3048)
			(end -0.67945 -0.3048)
			(stroke
				(width 0.1)
				(type default)
			)
			(layer "B.Fab")
		)
		(fp_line
			(start -0.12065 -0.2794)
			(end -0.12065 -0.3048)
			(stroke
				(width 0.1)
				(type default)
			)
			(layer "B.Fab")
		)
		(fp_line
			(start -0.120396 0.2794)
			(end 0.12065 0.2794)
			(stroke
				(width 0.1)
				(type default)
			)
			(layer "B.Fab")
		)
		(fp_line
			(start -0.120396 0.3048)
			(end -0.120396 0.2794)
			(stroke
				(width 0.1)
				(type default)
			)
			(layer "B.Fab")
		)
		(fp_line
			(start 0.12065 -0.305054)
			(end 0.12065 -0.2794)
			(stroke
				(width 0.1)
				(type default)
			)
			(layer "B.Fab")
		)
		(fp_line
			(start 0.12065 -0.2794)
			(end -0.12065 -0.2794)
			(stroke
				(width 0.1)
				(type default)
			)
			(layer "B.Fab")
		)
		(fp_line
			(start 0.12065 0.2794)
			(end 0.12065 0.3048)
			(stroke
				(width 0.1)
				(type default)
			)
			(layer "B.Fab")
		)
		(fp_line
			(start 0.12065 0.3048)
			(end 0.67945 0.3048)
			(stroke
				(width 0.1)
				(type default)
			)
			(layer "B.Fab")
		)
		(fp_line
			(start 0.67945 -0.305054)
			(end 0.12065 -0.305054)
			(stroke
				(width 0.1)
				(type default)
			)
			(layer "B.Fab")
		)
		(fp_line
			(start 0.67945 0.3048)
			(end 0.67945 -0.305054)
			(stroke
				(width 0.1)
				(type default)
			)
			(layer "B.Fab")
		)
		(pad "1" smd circle
			(at 0.40005 0 180)
			(size 0 0)
			(layers "B.Cu" "B.Mask" "B.Paste")
			(net "PVDD11_S3_P1")
		)
		(pad "2" smd circle
			(at -0.40005 0 180)
			(size 0 0)
			(layers "B.Cu" "B.Mask" "B.Paste")
			(net "GND")
		)
	)
	(footprint ""
		(layer "B.Cu")
		(at 303.518316 -396.393162 -90)
		(property "Reference" "C580"
			(at 0 0 90)
			(layer "B.SilkS")
			(hide yes)
			(effects
				(font
					(size 1.27 1.27)
				)
				(justify mirror)
			)
		)
		(property "Value" ""
			(at 0 0 90)
			(layer "B.Fab")
			(effects
				(font
					(size 1.27 1.27)
				)
				(justify mirror)
			)
		)
		(duplicate_pad_numbers_are_jumpers no)
		(fp_line
			(start -0.299974 0.150114)
			(end 0.299974 0.150114)
			(stroke
				(width 0.1)
				(type default)
			)
			(layer "B.Fab")
		)
		(fp_line
			(start 0.299974 0.150114)
			(end 0.299974 -0.150114)
			(stroke
				(width 0.1)
				(type default)
			)
			(layer "B.Fab")
		)
		(fp_line
			(start -0.299974 -0.150114)
			(end -0.299974 0.150114)
			(stroke
				(width 0.1)
				(type default)
			)
			(layer "B.Fab")
		)
		(fp_line
			(start 0.299974 -0.150114)
			(end -0.299974 -0.150114)
			(stroke
				(width 0.1)
				(type default)
			)
			(layer "B.Fab")
		)
		(pad "1" smd rect
			(at 0.2667 0 90)
			(size 0.3048 0.381)
			(layers "B.Cu" "B.Mask" "B.Paste")
			(net "P0V9_CPU0_RT0_2A")
		)
		(pad "2" smd rect
			(at -0.2667 0 90)
			(size 0.3048 0.381)
			(layers "B.Cu" "B.Mask" "B.Paste")
			(net "GND")
		)
	)
	(footprint ""
		(layer "B.Cu")
		(at 401.554696 -342.950292 -90)
		(property "Reference" "R943"
			(at 0 0 90)
			(layer "B.SilkS")
			(hide yes)
			(effects
				(font
					(size 1.27 1.27)
				)
				(justify mirror)
			)
		)
		(property "Value" ""
			(at 0 0 90)
			(layer "B.Fab")
			(effects
				(font
					(size 1.27 1.27)
				)
				(justify mirror)
			)
		)
		(duplicate_pad_numbers_are_jumpers no)
		(fp_line
			(start -0.7874 0.4064)
			(end 0.7874 0.4064)
			(stroke
				(width 0.1524)
				(type default)
			)
			(layer "B.SilkS")
		)
		(fp_line
			(start 0.7874 0.4064)
			(end 0.7874 -0.4064)
			(stroke
				(width 0.1524)
				(type default)
			)
			(layer "B.SilkS")
		)
		(fp_line
			(start -0.7874 -0.4064)
			(end -0.7874 0.4064)
			(stroke
				(width 0.1524)
				(type default)
			)
			(layer "B.SilkS")
		)
		(fp_line
			(start 0.7874 -0.4064)
			(end -0.7874 -0.4064)
			(stroke
				(width 0.1524)
				(type default)
			)
			(layer "B.SilkS")
		)
		(fp_line
			(start -0.67945 0.3048)
			(end -0.120396 0.3048)
			(stroke
				(width 0.1)
				(type default)
			)
			(layer "B.Fab")
		)
		(fp_line
			(start -0.120396 0.3048)
			(end -0.120396 0.2794)
			(stroke
				(width 0.1)
				(type default)
			)
			(layer "B.Fab")
		)
		(fp_line
			(start 0.12065 0.3048)
			(end 0.67945 0.3048)
			(stroke
				(width 0.1)
				(type default)
			)
			(layer "B.Fab")
		)
		(fp_line
			(start 0.67945 0.3048)
			(end 0.67945 -0.305054)
			(stroke
				(width 0.1)
				(type default)
			)
			(layer "B.Fab")
		)
		(fp_line
			(start -0.120396 0.2794)
			(end 0.12065 0.2794)
			(stroke
				(width 0.1)
				(type default)
			)
			(layer "B.Fab")
		)
		(fp_line
			(start 0.12065 0.2794)
			(end 0.12065 0.3048)
			(stroke
				(width 0.1)
				(type default)
			)
			(layer "B.Fab")
		)
		(fp_line
			(start -0.12065 -0.2794)
			(end -0.12065 -0.3048)
			(stroke
				(width 0.1)
				(type default)
			)
			(layer "B.Fab")
		)
		(fp_line
			(start 0.12065 -0.2794)
			(end -0.12065 -0.2794)
			(stroke
				(width 0.1)
				(type default)
			)
			(layer "B.Fab")
		)
		(fp_line
			(start -0.67945 -0.3048)
			(end -0.67945 0.3048)
			(stroke
				(width 0.1)
				(type default)
			)
			(layer "B.Fab")
		)
		(fp_line
			(start -0.12065 -0.3048)
			(end -0.67945 -0.3048)
			(stroke
				(width 0.1)
				(type default)
			)
			(layer "B.Fab")
		)
		(fp_line
			(start 0.12065 -0.305054)
			(end 0.12065 -0.2794)
			(stroke
				(width 0.1)
				(type default)
			)
			(layer "B.Fab")
		)
		(fp_line
			(start 0.67945 -0.305054)
			(end 0.12065 -0.305054)
			(stroke
				(width 0.1)
				(type default)
			)
			(layer "B.Fab")
		)
		(pad "1" smd circle
			(at 0.40005 0 90)
			(size 0 0)
			(layers "B.Cu" "B.Mask" "B.Paste")
			(net "P1V8_AUX")
		)
		(pad "2" smd circle
			(at -0.40005 0 90)
			(size 0 0)
			(layers "B.Cu" "B.Mask" "B.Paste")
			(net "FM_BIOS_POST_CMPLT_BUF_R1_N")
		)
	)
	(footprint ""
		(layer "B.Cu")
		(at 93.100144 -408.517344 90)
		(property "Reference" "C6689"
			(at 0 0 90)
			(layer "B.SilkS")
			(hide yes)
			(effects
				(font
					(size 1.27 1.27)
				)
				(justify mirror)
			)
		)
		(property "Value" ""
			(at 0 0 90)
			(layer "B.Fab")
			(effects
				(font
					(size 1.27 1.27)
				)
				(justify mirror)
			)
		)
		(duplicate_pad_numbers_are_jumpers no)
		(fp_line
			(start 0.299974 -0.150114)
			(end -0.299974 -0.150114)
			(stroke
				(width 0.1)
				(type default)
			)
			(layer "B.Fab")
		)
		(fp_line
			(start -0.299974 -0.150114)
			(end -0.299974 0.150114)
			(stroke
				(width 0.1)
				(type default)
			)
			(layer "B.Fab")
		)
		(fp_line
			(start 0.299974 0.150114)
			(end 0.299974 -0.150114)
			(stroke
				(width 0.1)
				(type default)
			)
			(layer "B.Fab")
		)
		(fp_line
			(start -0.299974 0.150114)
			(end 0.299974 0.150114)
			(stroke
				(width 0.1)
				(type default)
			)
			(layer "B.Fab")
		)
		(pad "1" smd rect
			(at 0.2667 0 270)
			(size 0.3048 0.381)
			(layers "B.Cu" "B.Mask" "B.Paste")
			(net "P5E_CPU1_P1_TX_BUF_C_DP<14>")
		)
		(pad "2" smd rect
			(at -0.2667 0 270)
			(size 0.3048 0.381)
			(layers "B.Cu" "B.Mask" "B.Paste")
			(net "P5E_CPU1_P1_TX_BUF_DP<14>")
		)
	)
)
